(kicad_pcb
	(version 20260206)
	(generator "pcbnew")
	(generator_version "10.0")
	(general
		(thickness 1.6)
		(legacy_teardrops no)
	)
	(paper "A4")
	(title_block
		(title "Bryce Canyon_R.DPB_16317-1_OCP.brd")
		(comment 1 "Bryce Canyon / footprints 828-833 of 2099")
	)
	(layers
		(0 "F.Cu" signal "TOP")
		(4 "In1.Cu" signal "L2GND")
		(6 "In2.Cu" signal "L3")
		(8 "In3.Cu" signal "L4VCC")
		(10 "In4.Cu" signal "L5VCC")
		(12 "In5.Cu" signal "L6")
		(14 "In6.Cu" signal "L7GND")
		(2 "B.Cu" signal "BOTTOM")
		(9 "F.Adhes" user "F.Adhesive")
		(11 "B.Adhes" user "B.Adhesive")
		(13 "F.Paste" user "Package Geometry/Pastemask Top")
		(15 "B.Paste" user "Package Geometry/Pastemask Bottom")
		(5 "F.SilkS" user "Ref Des/Silkscreen Top")
		(7 "B.SilkS" user "Ref Des/Silkscreen Bottom")
		(1 "F.Mask" user "Board Geometry/Soldermask Top")
		(3 "B.Mask" user "Board Geometry/Soldermask Bottom")
		(17 "Dwgs.User" user "User.Drawings")
		(19 "Cmts.User" user "User.Comments")
		(21 "Eco1.User" user "User.Eco1")
		(23 "Eco2.User" user "User.Eco2")
		(25 "Edge.Cuts" user "Board Geometry/Outline")
		(27 "Margin" user)
		(31 "F.CrtYd" user "Package Geometry/Place Bound Top")
		(29 "B.CrtYd" user "Package Geometry/Place Bound Bottom")
		(35 "F.Fab" user "Ref Des/Assembly Top")
		(33 "B.Fab" user "Ref Des/Assembly Bottom")
	)
	(footprint ""
		(layer "F.Cu")
		(at 47.960534 -110.398306 -90)
		(property "Reference" "R1123"
			(at 0 0 270)
			(layer "F.SilkS")
			(hide yes)
			(effects
				(font
					(size 1.27 1.27)
				)
			)
		)
		(property "Value" "3D01R5F-GP"
			(at 0 -8.9535 270)
			(unlocked yes)
			(layer "F.Fab")
			(hide yes)
			(effects
				(font
					(size 1.27 1.016)
					(thickness 0.1524)
				)
			)
		)
		(property "Device Type" "R805H24"
			(at 0 -10.6299 270)
			(unlocked yes)
			(layer "F.Fab")
			(hide yes)
			(effects
				(font
					(size 1.27 1.016)
					(thickness 0.1524)
				)
			)
		)
		(duplicate_pad_numbers_are_jumpers no)
		(fp_line
			(start -0.889 1.7018)
			(end 0.889 1.7018)
			(stroke
				(width 0.1524)
				(type default)
			)
			(layer "F.SilkS")
		)
		(fp_line
			(start 0.889 1.7018)
			(end 0.889 -0.508)
			(stroke
				(width 0.1524)
				(type default)
			)
			(layer "F.SilkS")
		)
		(fp_line
			(start -0.889 0.0762)
			(end -0.889 1.7018)
			(stroke
				(width 0.1524)
				(type default)
			)
			(layer "F.SilkS")
		)
		(fp_line
			(start -0.889 -1.7018)
			(end -0.889 0.2794)
			(stroke
				(width 0.1524)
				(type default)
			)
			(layer "F.SilkS")
		)
		(fp_line
			(start 0.889 -1.7018)
			(end 0.889 -0.381)
			(stroke
				(width 0.1524)
				(type default)
			)
			(layer "F.SilkS")
		)
		(fp_line
			(start 0.889 -1.7018)
			(end -0.889 -1.7018)
			(stroke
				(width 0.1524)
				(type default)
			)
			(layer "F.SilkS")
		)
		(fp_poly
			(pts
				(xy 0.9652 -1.778) (xy 0.9652 1.778) (xy -0.9652 1.778) (xy -0.9652 -1.778)
			)
			(stroke
				(width 0)
				(type default)
			)
			(fill no)
			(layer "F.CrtYd")
		)
		(fp_rect
			(start -0.9652 1.778)
			(end 0.9652 -1.778)
			(stroke
				(width 0)
				(type default)
			)
			(fill no)
			(layer "F.Fab")
		)
		(pad "1" smd rect
			(at 0 -0.9652 270)
			(size 1.397 1.143)
			(layers "F.Cu" "F.Mask" "F.Paste")
			(net "P5V_B_2_SNB")
		)
		(pad "2" smd rect
			(at 0 0.9652 270)
			(size 1.397 1.143)
			(layers "F.Cu" "F.Mask" "F.Paste")
			(net "GND")
		)
	)
	(footprint ""
		(layer "F.Cu")
		(at 231.013 -306.705 90)
		(property "Reference" "U18"
			(at 0 0 90)
			(layer "F.SilkS")
			(hide yes)
			(effects
				(font
					(size 1.27 1.27)
				)
			)
		)
		(property "Value" "SN74CBTLV3245APWR-GP"
			(at -0.889 -6.2738 90)
			(unlocked yes)
			(layer "F.Fab")
			(hide yes)
			(effects
				(font
					(size 1.016 1.016)
					(thickness 0.1524)
				)
			)
		)
		(property "Device Type" "TSOIC20H48"
			(at -0.9144 -7.8994 90)
			(unlocked yes)
			(layer "F.Fab")
			(hide yes)
			(effects
				(font
					(size 1.016 1.016)
					(thickness 0.1524)
				)
			)
		)
		(duplicate_pad_numbers_are_jumpers no)
		(fp_line
			(start 3.175 -1.397)
			(end 3.175 1.397)
			(stroke
				(width 0.2032)
				(type default)
			)
			(layer "F.SilkS")
		)
		(fp_line
			(start -3.556 -1.397)
			(end 3.175 -1.397)
			(stroke
				(width 0.2032)
				(type default)
			)
			(layer "F.SilkS")
		)
		(fp_line
			(start -3.556 -1.397)
			(end -3.556 4.064)
			(stroke
				(width 0.2032)
				(type default)
			)
			(layer "F.SilkS")
		)
		(fp_line
			(start -2.667 0)
			(end -3.556 -0.889)
			(stroke
				(width 0.2032)
				(type default)
			)
			(layer "F.SilkS")
		)
		(fp_line
			(start -2.667 0)
			(end -3.556 0.889)
			(stroke
				(width 0.2032)
				(type default)
			)
			(layer "F.SilkS")
		)
		(fp_line
			(start 3.175 1.397)
			(end -3.556 1.397)
			(stroke
				(width 0.2032)
				(type default)
			)
			(layer "F.SilkS")
		)
		(fp_line
			(start -3.556 1.397)
			(end -3.556 1.778)
			(stroke
				(width 0.2032)
				(type default)
			)
			(layer "F.SilkS")
		)
		(fp_line
			(start -3.556 4.064)
			(end -3.556 1.778)
			(stroke
				(width 0.508)
				(type default)
			)
			(layer "F.SilkS")
		)
		(fp_poly
			(pts
				(xy -3.25628 -1.8542) (xy 3.25628 -1.8542) (xy 3.25628 1.8542) (xy -3.25628 1.8542)
			)
			(stroke
				(width 0)
				(type default)
			)
			(fill yes)
			(layer "F.SilkS")
		)
		(fp_rect
			(start -3.556 3.81)
			(end 3.556 -3.81)
			(stroke
				(width 0)
				(type default)
			)
			(fill no)
			(layer "F.CrtYd")
		)
		(fp_poly
			(pts
				(xy -3.556 -3.81) (xy 3.556 -3.81) (xy 3.556 3.81) (xy -3.556 3.81)
			)
			(stroke
				(width 0)
				(type default)
			)
			(fill no)
			(layer "F.Fab")
		)
		(pad "1" smd rect
			(at -2.92608 2.8194 90)
			(size 0.3556 1.524)
			(layers "F.Cu" "F.Mask" "F.Paste")
			(net "Net_105")
		)
		(pad "2" smd rect
			(at -2.27584 2.8194 90)
			(size 0.3556 1.524)
			(layers "F.Cu" "F.Mask" "F.Paste")
			(net "FANTACH_A_F0")
		)
		(pad "3" smd rect
			(at -1.6256 2.8194 90)
			(size 0.3556 1.524)
			(layers "F.Cu" "F.Mask" "F.Paste")
			(net "FANTACH_A_R0")
		)
		(pad "4" smd rect
			(at -0.97536 2.8194 90)
			(size 0.3556 1.524)
			(layers "F.Cu" "F.Mask" "F.Paste")
			(net "FANTACH_A_F1")
		)
		(pad "5" smd rect
			(at -0.32512 2.8194 90)
			(size 0.3556 1.524)
			(layers "F.Cu" "F.Mask" "F.Paste")
			(net "FANTACH_A_R1")
		)
		(pad "6" smd rect
			(at 0.32512 2.8194 90)
			(size 0.3556 1.524)
			(layers "F.Cu" "F.Mask" "F.Paste")
			(net "FANTACH_A_F2")
		)
		(pad "7" smd rect
			(at 0.97536 2.8194 90)
			(size 0.3556 1.524)
			(layers "F.Cu" "F.Mask" "F.Paste")
			(net "FANTACH_A_R2")
		)
		(pad "8" smd rect
			(at 1.6256 2.8194 90)
			(size 0.3556 1.524)
			(layers "F.Cu" "F.Mask" "F.Paste")
			(net "FANTACH_A_F3")
		)
		(pad "9" smd rect
			(at 2.27584 2.8194 90)
			(size 0.3556 1.524)
			(layers "F.Cu" "F.Mask" "F.Paste")
			(net "FANTACH_A_R3")
		)
		(pad "10" smd rect
			(at 2.92608 2.8194 90)
			(size 0.3556 1.524)
			(layers "F.Cu" "F.Mask" "F.Paste")
			(net "GND")
		)
		(pad "11" smd rect
			(at 2.92608 -2.8194 90)
			(size 0.3556 1.524)
			(layers "F.Cu" "F.Mask" "F.Paste")
			(net "FANTACH_R3")
		)
		(pad "12" smd rect
			(at 2.27584 -2.8194 90)
			(size 0.3556 1.524)
			(layers "F.Cu" "F.Mask" "F.Paste")
			(net "FANTACH_F3")
		)
		(pad "13" smd rect
			(at 1.6256 -2.8194 90)
			(size 0.3556 1.524)
			(layers "F.Cu" "F.Mask" "F.Paste")
			(net "FANTACH_R2")
		)
		(pad "14" smd rect
			(at 0.97536 -2.8194 90)
			(size 0.3556 1.524)
			(layers "F.Cu" "F.Mask" "F.Paste")
			(net "FANTACH_F2")
		)
		(pad "15" smd rect
			(at 0.32512 -2.8194 90)
			(size 0.3556 1.524)
			(layers "F.Cu" "F.Mask" "F.Paste")
			(net "FANTACH_R1")
		)
		(pad "16" smd rect
			(at -0.32512 -2.8194 90)
			(size 0.3556 1.524)
			(layers "F.Cu" "F.Mask" "F.Paste")
			(net "FANTACH_F1")
		)
		(pad "17" smd rect
			(at -0.97536 -2.8194 90)
			(size 0.3556 1.524)
			(layers "F.Cu" "F.Mask" "F.Paste")
			(net "FANTACH_R0")
		)
		(pad "18" smd rect
			(at -1.6256 -2.8194 90)
			(size 0.3556 1.524)
			(layers "F.Cu" "F.Mask" "F.Paste")
			(net "FANTACH_F0")
		)
		(pad "19" smd rect
			(at -2.27584 -2.8194 90)
			(size 0.3556 1.524)
			(layers "F.Cu" "F.Mask" "F.Paste")
			(net "FANTACH_A_OE_N")
		)
		(pad "20" smd rect
			(at -2.92608 -2.8194 90)
			(size 0.3556 1.524)
			(layers "F.Cu" "F.Mask" "F.Paste")
			(net "P3V3_IN")
		)
	)
	(footprint ""
		(layer "F.Cu")
		(at 221.73946 -164.38626 90)
		(property "Reference" "R58"
			(at 0 0 90)
			(layer "F.SilkS")
			(hide yes)
			(effects
				(font
					(size 1.27 1.27)
				)
			)
		)
		(property "Value" "4K7R2F-GP"
			(at 0.064008 -3.993896 90)
			(unlocked yes)
			(layer "F.Fab")
			(hide yes)
			(effects
				(font
					(size 1.016 1.016)
					(thickness 0.1524)
				)
			)
		)
		(property "Device Type" "R402H16"
			(at 0.064008 -5.517896 90)
			(unlocked yes)
			(layer "F.Fab")
			(hide yes)
			(effects
				(font
					(size 1.016 1.016)
					(thickness 0.1524)
				)
			)
		)
		(duplicate_pad_numbers_are_jumpers no)
		(fp_line
			(start 0.508 -0.9398)
			(end -0.508 -0.9398)
			(stroke
				(width 0.1524)
				(type default)
			)
			(layer "F.SilkS")
		)
		(fp_line
			(start -0.508 -0.9398)
			(end -0.508 0.9398)
			(stroke
				(width 0.1524)
				(type default)
			)
			(layer "F.SilkS")
		)
		(fp_rect
			(start -0.508 0.9398)
			(end 0.508 -0.9398)
			(stroke
				(width 0)
				(type default)
			)
			(fill no)
			(layer "F.CrtYd")
		)
		(fp_rect
			(start -0.508 0.9398)
			(end 0.508 -0.9398)
			(stroke
				(width 0)
				(type default)
			)
			(fill no)
			(layer "F.Fab")
		)
		(pad "1" smd custom
			(at 0 -0.4445 90)
			(size 0.1397 0.1397)
			(layers "F.Cu" "F.Mask" "F.Paste")
			(net "IO_EXP6_A1")
			(options
				(clearance outline)
				(anchor circle)
			)
			(primitives
				(gr_poly
					(pts
						(arc
							(start -0.1778 -0.2794)
							(mid -0.249642 -0.249642)
							(end -0.2794 -0.1778)
						)
						(arc
							(start -0.2794 0.1778)
							(mid -0.249642 0.249642)
							(end -0.1778 0.2794)
						)
						(arc
							(start 0.1778 0.2794)
							(mid 0.249642 0.249642)
							(end 0.2794 0.1778)
						)
						(arc
							(start 0.2794 -0.1778)
							(mid 0.249642 -0.249642)
							(end 0.1778 -0.2794)
						)
					)
					(width 0)
					(fill yes)
				)
			)
		)
		(pad "2" smd custom
			(at 0 0.4445 90)
			(size 0.1397 0.1397)
			(layers "F.Cu" "F.Mask" "F.Paste")
			(net "GND")
			(options
				(clearance outline)
				(anchor circle)
			)
			(primitives
				(gr_poly
					(pts
						(arc
							(start -0.1778 -0.2794)
							(mid -0.249642 -0.249642)
							(end -0.2794 -0.1778)
						)
						(arc
							(start -0.2794 0.1778)
							(mid -0.249642 0.249642)
							(end -0.1778 0.2794)
						)
						(arc
							(start 0.1778 0.2794)
							(mid 0.249642 0.249642)
							(end 0.2794 0.1778)
						)
						(arc
							(start 0.2794 -0.1778)
							(mid 0.249642 -0.249642)
							(end 0.1778 -0.2794)
						)
					)
					(width 0)
					(fill yes)
				)
			)
		)
	)
	(footprint ""
		(layer "F.Cu")
		(at 109.73435 -102.351586 -90)
		(property "Reference" "R378"
			(at 0 0 270)
			(layer "F.SilkS")
			(hide yes)
			(effects
				(font
					(size 1.27 1.27)
				)
			)
		)
		(property "Value" "4K7R2F-GP"
			(at 0.064008 -3.993896 270)
			(unlocked yes)
			(layer "F.Fab")
			(hide yes)
			(effects
				(font
					(size 1.016 1.016)
					(thickness 0.1524)
				)
			)
		)
		(property "Device Type" "R402H16"
			(at 0.064008 -5.517896 270)
			(unlocked yes)
			(layer "F.Fab")
			(hide yes)
			(effects
				(font
					(size 1.016 1.016)
					(thickness 0.1524)
				)
			)
		)
		(duplicate_pad_numbers_are_jumpers no)
		(fp_line
			(start -0.508 -0.9398)
			(end -0.508 0.9398)
			(stroke
				(width 0.1524)
				(type default)
			)
			(layer "F.SilkS")
		)
		(fp_line
			(start 0.508 -0.9398)
			(end -0.508 -0.9398)
			(stroke
				(width 0.1524)
				(type default)
			)
			(layer "F.SilkS")
		)
		(fp_rect
			(start -0.508 0.9398)
			(end 0.508 -0.9398)
			(stroke
				(width 0)
				(type default)
			)
			(fill no)
			(layer "F.CrtYd")
		)
		(fp_rect
			(start -0.508 0.9398)
			(end 0.508 -0.9398)
			(stroke
				(width 0)
				(type default)
			)
			(fill no)
			(layer "F.Fab")
		)
		(pad "1" smd custom
			(at 0 -0.4445 270)
			(size 0.1397 0.1397)
			(layers "F.Cu" "F.Mask" "F.Paste")
			(net "DRIVE_B_15_FLT_LED")
			(options
				(clearance outline)
				(anchor circle)
			)
			(primitives
				(gr_poly
					(pts
						(arc
							(start -0.1778 -0.2794)
							(mid -0.249642 -0.249642)
							(end -0.2794 -0.1778)
						)
						(arc
							(start -0.2794 0.1778)
							(mid -0.249642 0.249642)
							(end -0.1778 0.2794)
						)
						(arc
							(start 0.1778 0.2794)
							(mid 0.249642 0.249642)
							(end 0.2794 0.1778)
						)
						(arc
							(start 0.2794 -0.1778)
							(mid 0.249642 -0.249642)
							(end 0.1778 -0.2794)
						)
					)
					(width 0)
					(fill yes)
				)
			)
		)
		(pad "2" smd custom
			(at 0 0.4445 270)
			(size 0.1397 0.1397)
			(layers "F.Cu" "F.Mask" "F.Paste")
			(net "GND")
			(options
				(clearance outline)
				(anchor circle)
			)
			(primitives
				(gr_poly
					(pts
						(arc
							(start -0.1778 -0.2794)
							(mid -0.249642 -0.249642)
							(end -0.2794 -0.1778)
						)
						(arc
							(start -0.2794 0.1778)
							(mid -0.249642 0.249642)
							(end -0.1778 0.2794)
						)
						(arc
							(start 0.1778 0.2794)
							(mid 0.249642 0.249642)
							(end 0.2794 0.1778)
						)
						(arc
							(start 0.2794 -0.1778)
							(mid 0.249642 -0.249642)
							(end 0.1778 -0.2794)
						)
					)
					(width 0)
					(fill yes)
				)
			)
		)
	)
	(footprint ""
		(layer "F.Cu")
		(at 23.876 -157.226)
		(property "Reference" "C192"
			(at 0 0 0)
			(layer "F.SilkS")
			(hide yes)
			(effects
				(font
					(size 1.27 1.27)
				)
			)
		)
		(property "Value" "SC4D7U25V5KX-1-GP"
			(at -0.0762 -6.1214 0)
			(unlocked yes)
			(layer "F.Fab")
			(hide yes)
			(effects
				(font
					(size 1.016 1.016)
					(thickness 0.1524)
				)
			)
		)
		(property "Device Type" "C805H58"
			(at -0.0762 -8.1534 0)
			(unlocked yes)
			(layer "F.Fab")
			(hide yes)
			(effects
				(font
					(size 1.016 1.016)
					(thickness 0.1524)
				)
			)
		)
		(duplicate_pad_numbers_are_jumpers no)
		(fp_line
			(start 0.635 0)
			(end -0.635 0)
			(stroke
				(width 0.508)
				(type default)
			)
			(layer "F.SilkS")
		)
		(fp_rect
			(start -0.9652 1.778)
			(end 0.9652 -1.778)
			(stroke
				(width 0)
				(type default)
			)
			(fill no)
			(layer "F.CrtYd")
		)
		(fp_poly
			(pts
				(xy -0.9652 -1.778) (xy 0.9652 -1.778) (xy 0.9652 1.778) (xy -0.9652 1.778)
			)
			(stroke
				(width 0)
				(type default)
			)
			(fill no)
			(layer "F.Fab")
		)
		(pad "1" smd rect
			(at 0 -0.9652)
			(size 1.397 1.143)
			(layers "F.Cu" "F.Mask" "F.Paste")
			(net "P12V_HDD12")
		)
		(pad "2" smd rect
			(at 0 0.9652)
			(size 1.397 1.143)
			(layers "F.Cu" "F.Mask" "F.Paste")
			(net "GND")
		)
	)
	(footprint ""
		(layer "F.Cu")
		(at 239.268 -227.076 -90)
		(property "Reference" "C17"
			(at 0 0 270)
			(layer "F.SilkS")
			(hide yes)
			(effects
				(font
					(size 1.27 1.27)
				)
			)
		)
		(property "Value" "SC1U16V3KX-5GP"
			(at 0 -2.8194 270)
			(unlocked yes)
			(layer "F.Fab")
			(hide yes)
			(effects
				(font
					(size 1.016 1.016)
					(thickness 0.1524)
				)
			)
		)
		(property "Device Type" "C603H36"
			(at 0 -4.3434 270)
			(unlocked yes)
			(layer "F.Fab")
			(hide yes)
			(effects
				(font
					(size 1.016 1.016)
					(thickness 0.1524)
				)
			)
		)
		(duplicate_pad_numbers_are_jumpers no)
		(fp_line
			(start 0.508 0)
			(end -0.508 0)
			(stroke
				(width 0.2032)
				(type default)
			)
			(layer "F.SilkS")
		)
		(fp_rect
			(start -0.5842 1.3335)
			(end 0.5842 -1.3335)
			(stroke
				(width 0)
				(type default)
			)
			(fill no)
			(layer "F.CrtYd")
		)
		(fp_rect
			(start -0.5842 1.3335)
			(end 0.5842 -1.3335)
			(stroke
				(width 0)
				(type default)
			)
			(fill no)
			(layer "F.Fab")
		)
		(pad "1" smd custom
			(at 0 -0.762 270)
			(size 0.2159 0.2159)
			(layers "F.Cu" "F.Mask" "F.Paste")
			(net "GPIO_VCC_U10")
			(options
				(clearance outline)
				(anchor circle)
			)
			(primitives
				(gr_poly
					(pts
						(arc
							(start -0.3302 -0.4318)
							(mid -0.402042 -0.402042)
							(end -0.4318 -0.3302)
						)
						(arc
							(start -0.4318 0.3302)
							(mid -0.402042 0.402042)
							(end -0.3302 0.4318)
						)
						(arc
							(start 0.3302 0.4318)
							(mid 0.402042 0.402042)
							(end 0.4318 0.3302)
						)
						(arc
							(start 0.4318 -0.3302)
							(mid 0.402042 -0.402042)
							(end 0.3302 -0.4318)
						)
					)
					(width 0)
					(fill yes)
				)
			)
		)
		(pad "2" smd custom
			(at 0 0.762 270)
			(size 0.2159 0.2159)
			(layers "F.Cu" "F.Mask" "F.Paste")
			(net "GND")
			(options
				(clearance outline)
				(anchor circle)
			)
			(primitives
				(gr_poly
					(pts
						(arc
							(start -0.3302 -0.4318)
							(mid -0.402042 -0.402042)
							(end -0.4318 -0.3302)
						)
						(arc
							(start -0.4318 0.3302)
							(mid -0.402042 0.402042)
							(end -0.3302 0.4318)
						)
						(arc
							(start 0.3302 0.4318)
							(mid 0.402042 0.402042)
							(end 0.4318 0.3302)
						)
						(arc
							(start 0.4318 -0.3302)
							(mid 0.402042 -0.402042)
							(end 0.3302 -0.4318)
						)
					)
					(width 0)
					(fill yes)
				)
			)
		)
	)
)
